# S9S_MB_2U (Grand Teton) — schematic netlist excerpt (pin names and nets, part order shuffled) for the footprints in the layout excerpt that follows; sources: Cadence DE-HDL packaged netlist, KiCad conversion of 03242023_DA0F0TMBIJ0_F0T_Motherboard_J_brd_V01_OCP.brd

R3181  Q_RES  27.4 1% CHIP  pkg 0402LF  page 155 : A = CLK_50M_NCSI_OCP_2 ; B = CLK_50M_NCSI_OCP_V3_2

(kicad_pcb
	(version 20260206)
	(generator "pcbnew")
	(generator_version "10.0")
	(general
		(thickness 1.6)
		(legacy_teardrops no)
	)
	(paper "A4")
	(title_block
		(title "03242023_DA0F0TMBIJ0_F0T_Motherboard_J_brd_V01_OCP.brd")
		(comment 1 "Grand Teton / footprints 646-646 of 6105")
	)
	(layers
		(0 "F.Cu" signal "TOP")
		(4 "In1.Cu" signal "GND")
		(6 "In2.Cu" signal "IN1")
		(8 "In3.Cu" signal "GND1")
		(10 "In4.Cu" signal "IN2")
		(12 "In5.Cu" signal "GND2")
		(14 "In6.Cu" signal "IN3")
		(16 "In7.Cu" signal "GND3")
		(18 "In8.Cu" signal "VCC")
		(20 "In9.Cu" signal "VCC1")
		(22 "In10.Cu" signal "GND4")
		(24 "In11.Cu" signal "IN4")
		(26 "In12.Cu" signal "GND5")
		(28 "In13.Cu" signal "IN5")
		(30 "In14.Cu" signal "GND6")
		(32 "In15.Cu" signal "IN6")
		(34 "In16.Cu" signal "GND7")
		(2 "B.Cu" signal "BOTTOM")
		(9 "F.Adhes" user "F.Adhesive")
		(11 "B.Adhes" user "B.Adhesive")
		(13 "F.Paste" user "Package Geometry/Pastemask Top")
		(15 "B.Paste" user "Package Geometry/Pastemask Bottom")
		(5 "F.SilkS" user "Ref Des/Silkscreen Top")
		(7 "B.SilkS" user "Ref Des/Silkscreen Bottom")
		(1 "F.Mask" user "Board Geometry/Soldermask Top")
		(3 "B.Mask" user "Board Geometry/Soldermask Bottom")
		(17 "Dwgs.User" user "User.Drawings")
		(19 "Cmts.User" user "User.Comments")
		(21 "Eco1.User" user "User.Eco1")
		(23 "Eco2.User" user "User.Eco2")
		(25 "Edge.Cuts" user "Board Geometry/Outline")
		(27 "Margin" user)
		(31 "F.CrtYd" user "Package Geometry/Place Bound Top")
		(29 "B.CrtYd" user "Package Geometry/Place Bound Bottom")
		(35 "F.Fab" user "Ref Des/Assembly Top")
		(33 "B.Fab" user "Ref Des/Assembly Bottom")
	)
	(footprint ""
		(layer "F.Cu")
		(at 217.583766 -16.381222 -90)
		(property "Reference" "R3181"
			(at 0 0 270)
			(layer "F.SilkS")
			(hide yes)
			(effects
				(font
					(size 1.27 1.27)
				)
			)
		)
		(property "Value" ""
			(at 0 0 270)
			(layer "F.Fab")
			(effects
				(font
					(size 1.27 1.27)
				)
			)
		)
		(duplicate_pad_numbers_are_jumpers no)
		(fp_line
			(start -0.7874 0.4064)
			(end -0.7874 -0.4064)
			(stroke
				(width 0.1524)
				(type default)
			)
			(layer "F.SilkS")
		)
		(fp_line
			(start 0.7874 0.4064)
			(end -0.7874 0.4064)
			(stroke
				(width 0.1524)
				(type default)
			)
			(layer "F.SilkS")
		)
		(fp_line
			(start -0.7874 -0.4064)
			(end 0.7874 -0.4064)
			(stroke
				(width 0.1524)
				(type default)
			)
			(layer "F.SilkS")
		)
		(fp_line
			(start 0.7874 -0.4064)
			(end 0.7874 0.4064)
			(stroke
				(width 0.1524)
				(type default)
			)
			(layer "F.SilkS")
		)
		(fp_line
			(start -0.67945 0.3048)
			(end -0.67945 -0.305054)
			(stroke
				(width 0.1)
				(type default)
			)
			(layer "F.Fab")
		)
		(fp_line
			(start -0.12065 0.3048)
			(end -0.67945 0.3048)
			(stroke
				(width 0.1)
				(type default)
			)
			(layer "F.Fab")
		)
		(fp_line
			(start 0.120396 0.3048)
			(end 0.120396 0.2794)
			(stroke
				(width 0.1)
				(type default)
			)
			(layer "F.Fab")
		)
		(fp_line
			(start 0.67945 0.3048)
			(end 0.120396 0.3048)
			(stroke
				(width 0.1)
				(type default)
			)
			(layer "F.Fab")
		)
		(fp_line
			(start -0.12065 0.2794)
			(end -0.12065 0.3048)
			(stroke
				(width 0.1)
				(type default)
			)
			(layer "F.Fab")
		)
		(fp_line
			(start 0.120396 0.2794)
			(end -0.12065 0.2794)
			(stroke
				(width 0.1)
				(type default)
			)
			(layer "F.Fab")
		)
		(fp_line
			(start -0.12065 -0.2794)
			(end 0.12065 -0.2794)
			(stroke
				(width 0.1)
				(type default)
			)
			(layer "F.Fab")
		)
		(fp_line
			(start 0.12065 -0.2794)
			(end 0.12065 -0.3048)
			(stroke
				(width 0.1)
				(type default)
			)
			(layer "F.Fab")
		)
		(fp_line
			(start 0.12065 -0.3048)
			(end 0.67945 -0.3048)
			(stroke
				(width 0.1)
				(type default)
			)
			(layer "F.Fab")
		)
		(fp_line
			(start 0.67945 -0.3048)
			(end 0.67945 0.3048)
			(stroke
				(width 0.1)
				(type default)
			)
			(layer "F.Fab")
		)
		(fp_line
			(start -0.67945 -0.305054)
			(end -0.12065 -0.305054)
			(stroke
				(width 0.1)
				(type default)
			)
			(layer "F.Fab")
		)
		(fp_line
			(start -0.12065 -0.305054)
			(end -0.12065 -0.2794)
			(stroke
				(width 0.1)
				(type default)
			)
			(layer "F.Fab")
		)
		(pad "1" smd circle
			(at -0.40005 0 270)
			(size 0 0)
			(layers "F.Cu" "F.Mask" "F.Paste")
			(net "CLK_50M_NCSI_OCP_2")
		)
		(pad "2" smd circle
			(at 0.40005 0 270)
			(size 0 0)
			(layers "F.Cu" "F.Mask" "F.Paste")
			(net "CLK_50M_NCSI_OCP_V3_2")
		)
	)
)
